#ISCELL
  mstr_misc dns *
  *
#ISCELL
  pure_quanta quanta_title_block_c *
  *
#CELL
  pure_quanta mosfet_n *
  page168_i1
#ISCELL
  pure_quanta_power universal_gnd *
  page168_i10
#CELL
  pure_quanta q_cap *
  page168_i100
#CELL
  pure_quanta q_res *
  page168_i101
#ISCELL
  pure_quanta_power universal_gnd *
  page168_i102
#ISCELL
  pure_quanta_power vcc_core *
  page168_i103
#CELL
  pure_quanta q_res *
  page168_i104
#CELL
  pure_quanta q_res *
  page168_i105
#ISCELL
  pure_quanta_power universal_gnd *
  page168_i107
#ISCELL
  pure_quanta_power universal_gnd *
  page168_i108
#ISCELL
  pure_quanta_power vcc_core *
  page168_i109
#ISCELL
  standard offpage *
  page168_i110
#ISCELL
  pure_quanta_power vcc_core *
  page168_i111
#CELL
  pure_quanta q_res *
  page168_i112
#CELL
  pure_quanta q_res *
  page168_i113
#CELL
  pure_quanta q_cap *
  page168_i114
#ISCELL
  pure_quanta_power universal_gnd *
  page168_i116
#CELL
  pure_quanta q_cap *
  page168_i118
#ISCELL
  standard offpage *
  page168_i119
#ISCELL
  pure_quanta_power universal_gnd *
  page168_i12
#CELL
  pure_quanta conn3_hbb1031l300d8h *
  page168_i123
#ISCELL
  pure_quanta_power universal_gnd *
  page168_i124
#CELL
  pure_quanta q_cap *
  page168_i13
#CELL
  pure_quanta q_res *
  page168_i139
#ISCELL
  pure_quanta_power vcc_core *
  page168_i14
#CELL
  pure_quanta q_cap *
  page168_i140
#ISCELL
  pure_quanta_power universal_gnd *
  page168_i141
#ISCELL
  pure_quanta_power universal_gnd *
  page168_i144
#ISCELL
  pure_quanta_power universal_gnd *
  page168_i145
#CELL
  pure_quanta q_res *
  page168_i148
#CELL
  pure_quanta q_res *
  page168_i149
#ISCELL
  standard offpage *
  page168_i15
#ISCELL
  standard offpage *
  page168_i150
#CELL
  pure_quanta q_res *
  page168_i151
#ISCELL
  standard offpage *
  page168_i152
#ISCELL
  standard offpage *
  page168_i153
#CELL
  pure_quanta mosfet_pch_gds_esd_protected *
  page168_i154
#ISCELL
  pure_quanta_power universal_gnd *
  page168_i155
#CELL
  pure_quanta q_cap *
  page168_i156
#ISCELL
  pure_quanta_power universal_gnd *
  page168_i157
#CELL
  pure_quanta q_cap *
  page168_i158
#ISCELL
  standard offpage *
  page168_i167
#ISCELL
  pure_quanta_power vcc_core *
  page168_i168
#ISCELL
  pure_quanta_power universal_gnd *
  page168_i169
#CELL
  pure_quanta q_cap *
  page168_i170
#ISCELL
  standard offpage *
  page168_i171
#ISCELL
  pure_quanta_power vcc_core *
  page168_i172
#CELL
  pure_quanta q_res *
  page168_i173
#CELL
  pure_quanta q_res *
  page168_i174
#CELL
  pure_quanta q_res *
  page168_i175
#CELL
  pure_quanta q_res *
  page168_i176
#ISCELL
  standard offpage *
  page168_i183
#ISCELL
  standard offpage *
  page168_i186
#ISCELL
  standard offpage *
  page168_i187
#CELL
  pure_quanta q_cap *
  page168_i214
#CELL
  pure_quanta q_cap *
  page168_i215
#CELL
  pure_quanta q_cap *
  page168_i216
#ISCELL
  pure_quanta_power universal_gnd *
  page168_i217
#ISCELL
  standard offpage *
  page168_i220
#ISCELL
  standard offpage *
  page168_i221
#ISCELL
  standard offpage *
  page168_i222
#ISCELL
  standard offpage *
  page168_i223
#ISCELL
  standard offpage *
  page168_i224
#ISCELL
  standard offpage *
  page168_i225
#ISCELL
  standard offpage *
  page168_i226
#ISCELL
  standard offpage *
  page168_i227
#ISCELL
  standard offpage *
  page168_i228
#ISCELL
  standard offpage *
  page168_i229
#ISCELL
  standard offpage *
  page168_i230
#ISCELL
  standard offpage *
  page168_i231
#CELL
  pure_quanta q_res *
  page168_i232
#ISCELL
  pure_quanta_power universal_gnd *
  page168_i233
#ISCELL
  pure_quanta_power universal_gnd *
  page168_i234
#CELL
  pure_quanta q_res *
  page168_i235
#ISCELL
  standard offpage *
  page168_i236
#ISCELL
  standard offpage *
  page168_i237
#ISCELL
  standard offpage *
  page168_i238
#ISCELL
  standard offpage *
  page168_i239
#ISCELL
  standard offpage *
  page168_i240
#ISCELL
  standard offpage *
  page168_i241
#ISCELL
  pure_quanta_power universal_gnd *
  page168_i242
#CELL
  pure_quanta q_res *
  page168_i243
#CELL
  pure_quanta q_res *
  page168_i244
#ISCELL
  pure_quanta_power universal_gnd *
  page168_i245
#CELL
  pure_quanta q_res *
  page168_i3
#CELL
  pure_quanta q_cap *
  page168_i35
#CELL
  pure_quanta q_cap *
  page168_i36
#ISCELL
  pure_quanta_power universal_gnd *
  page168_i37
#ISCELL
  pure_quanta_power universal_gnd *
  page168_i38
#CELL
  pure_quanta q_res *
  page168_i4
#CELL
  pure_quanta q_res *
  page168_i41
#CELL
  pure_quanta q_cap *
  page168_i42
#CELL
  pure_quanta q_res *
  page168_i43
#ISCELL
  pure_quanta_power universal_gnd *
  page168_i44
#ISCELL
  standard offpage *
  page168_i45
#ISCELL
  pure_quanta_power vcc_core *
  page168_i46
#CELL
  pure_quanta q_res *
  page168_i47
#CELL
  pure_quanta q_cap *
  page168_i49
#ISCELL
  pure_quanta_power universal_gnd *
  page168_i5
#ISCELL
  pure_quanta_power universal_gnd *
  page168_i50
#CELL
  pure_quanta q_res *
  page168_i55
#CELL
  pure_quanta q_res *
  page168_i56
#CELL
  pure_quanta q_res *
  page168_i57
#CELL
  pure_quanta q_res *
  page168_i58
#ISCELL
  pure_quanta_power vcc_core *
  page168_i59
#ISCELL
  pure_quanta_power vcc_core *
  page168_i6
#CELL
  pure_quanta q_res *
  page168_i62
#CELL
  pure_quanta q_res *
  page168_i63
#ISCELL
  pure_quanta_power universal_gnd *
  page168_i64
#ISCELL
  pure_quanta_power universal_gnd *
  page168_i65
#CELL
  pure_quanta q_res *
  page168_i66
#CELL
  pure_quanta q_res *
  page168_i67
#CELL
  pure_quanta q_res *
  page168_i68
#CELL
  pure_quanta raa229620gnpha0 *
  page168_i7
#ISCELL
  standard offpage *
  page168_i73
#ISCELL
  standard offpage *
  page168_i74
#ISCELL
  standard offpage *
  page168_i75
#CELL
  pure_quanta q_cap *
  page168_i76
#CELL
  pure_quanta q_res *
  page168_i77
#ISCELL
  standard offpage *
  page168_i79
#CELL
  pure_quanta q_cap *
  page168_i8
#ISCELL
  standard offpage *
  page168_i80
#CELL
  pure_quanta q_res *
  page168_i81
#CELL
  pure_quanta q_res *
  page168_i82
#ISCELL
  pure_quanta_power universal_gnd *
  page168_i83
#ISCELL
  pure_quanta_power vcc_core *
  page168_i84
#ISCELL
  pure_quanta_power vcc_core *
  page168_i85
#CELL
  pure_quanta q_res *
  page168_i86
#CELL
  pure_quanta q_cap *
  page168_i87
#CELL
  pure_quanta q_res *
  page168_i88
#CELL
  pure_quanta q_res *
  page168_i90
#ISCELL
  pure_quanta_power universal_gnd *
  page168_i91
#ISCELL
  standard offpage *
  page168_i92
#ISCELL
  standard offpage *
  page168_i93
#ISCELL
  pure_quanta_power universal_gnd *
  page168_i99
